# S9S_MB_2U (Grand Teton) — schematic netlist excerpt (pin names and nets, part order shuffled) for the footprints in the layout excerpt that follows; sources: Cadence DE-HDL packaged netlist, KiCad conversion of 03242023_DA0F0TMBIJ0_F0T_Motherboard_J_brd_V01_OCP.brd

R3767  Q_RES  0.01 1% CHIP  pkg 2512LF  page 171 : A = P3V3_E1S_0 ; B = P3V3_E1S_0_R
PC194  Q_CAP  100NF 50V 10% X7R  pkg C0402  page 275 : A = SW_PVCCINFAON_CPU0_BOOT2_R ; B = SW_PVCCINFAON_CPU0_BOOTR2
R1089  Q_RES  2.2K 5% CHIP  pkg 0402LF  page 231 : A = P3V3_AUX ; B = SMB_SENSOR_M2_P0_3V3AUX_SCL

(kicad_pcb
	(version 20260206)
	(generator "pcbnew")
	(generator_version "10.0")
	(general
		(thickness 1.6)
		(legacy_teardrops no)
	)
	(paper "A4")
	(title_block
		(title "03242023_DA0F0TMBIJ0_F0T_Motherboard_J_brd_V01_OCP.brd")
		(comment 1 "Grand Teton / footprints 792-794 of 6105")
	)
	(layers
		(0 "F.Cu" signal "TOP")
		(4 "In1.Cu" signal "GND")
		(6 "In2.Cu" signal "IN1")
		(8 "In3.Cu" signal "GND1")
		(10 "In4.Cu" signal "IN2")
		(12 "In5.Cu" signal "GND2")
		(14 "In6.Cu" signal "IN3")
		(16 "In7.Cu" signal "GND3")
		(18 "In8.Cu" signal "VCC")
		(20 "In9.Cu" signal "VCC1")
		(22 "In10.Cu" signal "GND4")
		(24 "In11.Cu" signal "IN4")
		(26 "In12.Cu" signal "GND5")
		(28 "In13.Cu" signal "IN5")
		(30 "In14.Cu" signal "GND6")
		(32 "In15.Cu" signal "IN6")
		(34 "In16.Cu" signal "GND7")
		(2 "B.Cu" signal "BOTTOM")
		(9 "F.Adhes" user "F.Adhesive")
		(11 "B.Adhes" user "B.Adhesive")
		(13 "F.Paste" user "Package Geometry/Pastemask Top")
		(15 "B.Paste" user "Package Geometry/Pastemask Bottom")
		(5 "F.SilkS" user "Ref Des/Silkscreen Top")
		(7 "B.SilkS" user "Ref Des/Silkscreen Bottom")
		(1 "F.Mask" user "Board Geometry/Soldermask Top")
		(3 "B.Mask" user "Board Geometry/Soldermask Bottom")
		(17 "Dwgs.User" user "User.Drawings")
		(19 "Cmts.User" user "User.Comments")
		(21 "Eco1.User" user "User.Eco1")
		(23 "Eco2.User" user "User.Eco2")
		(25 "Edge.Cuts" user "Board Geometry/Outline")
		(27 "Margin" user)
		(31 "F.CrtYd" user "Package Geometry/Place Bound Top")
		(29 "B.CrtYd" user "Package Geometry/Place Bound Bottom")
		(35 "F.Fab" user "Ref Des/Assembly Top")
		(33 "B.Fab" user "Ref Des/Assembly Bottom")
	)
	(footprint ""
		(layer "F.Cu")
		(at 420.4716 -177.724562 180)
		(property "Reference" "PC194"
			(at 0 0 180)
			(layer "F.SilkS")
			(hide yes)
			(effects
				(font
					(size 1.27 1.27)
				)
			)
		)
		(property "Value" ""
			(at 0 0 180)
			(layer "F.Fab")
			(effects
				(font
					(size 1.27 1.27)
				)
			)
		)
		(duplicate_pad_numbers_are_jumpers no)
		(fp_line
			(start 0.7874 0.4064)
			(end -0.7874 0.4064)
			(stroke
				(width 0.1524)
				(type default)
			)
			(layer "F.SilkS")
		)
		(fp_line
			(start 0.7874 -0.4064)
			(end 0.7874 0.4064)
			(stroke
				(width 0.1524)
				(type default)
			)
			(layer "F.SilkS")
		)
		(fp_line
			(start -0.7874 0.4064)
			(end -0.7874 -0.4064)
			(stroke
				(width 0.1524)
				(type default)
			)
			(layer "F.SilkS")
		)
		(fp_line
			(start -0.7874 -0.4064)
			(end 0.7874 -0.4064)
			(stroke
				(width 0.1524)
				(type default)
			)
			(layer "F.SilkS")
		)
		(fp_line
			(start 0.67945 0.3048)
			(end 0.120396 0.3048)
			(stroke
				(width 0.1)
				(type default)
			)
			(layer "F.Fab")
		)
		(fp_line
			(start 0.67945 -0.3048)
			(end 0.67945 0.3048)
			(stroke
				(width 0.1)
				(type default)
			)
			(layer "F.Fab")
		)
		(fp_line
			(start 0.12065 -0.2794)
			(end 0.12065 -0.3048)
			(stroke
				(width 0.1)
				(type default)
			)
			(layer "F.Fab")
		)
		(fp_line
			(start 0.12065 -0.3048)
			(end 0.67945 -0.3048)
			(stroke
				(width 0.1)
				(type default)
			)
			(layer "F.Fab")
		)
		(fp_line
			(start 0.120396 0.3048)
			(end 0.120396 0.2794)
			(stroke
				(width 0.1)
				(type default)
			)
			(layer "F.Fab")
		)
		(fp_line
			(start 0.120396 0.2794)
			(end -0.12065 0.2794)
			(stroke
				(width 0.1)
				(type default)
			)
			(layer "F.Fab")
		)
		(fp_line
			(start -0.12065 0.3048)
			(end -0.67945 0.3048)
			(stroke
				(width 0.1)
				(type default)
			)
			(layer "F.Fab")
		)
		(fp_line
			(start -0.12065 0.2794)
			(end -0.12065 0.3048)
			(stroke
				(width 0.1)
				(type default)
			)
			(layer "F.Fab")
		)
		(fp_line
			(start -0.12065 -0.2794)
			(end 0.12065 -0.2794)
			(stroke
				(width 0.1)
				(type default)
			)
			(layer "F.Fab")
		)
		(fp_line
			(start -0.12065 -0.305054)
			(end -0.12065 -0.2794)
			(stroke
				(width 0.1)
				(type default)
			)
			(layer "F.Fab")
		)
		(fp_line
			(start -0.67945 0.3048)
			(end -0.67945 -0.305054)
			(stroke
				(width 0.1)
				(type default)
			)
			(layer "F.Fab")
		)
		(fp_line
			(start -0.67945 -0.305054)
			(end -0.12065 -0.305054)
			(stroke
				(width 0.1)
				(type default)
			)
			(layer "F.Fab")
		)
		(pad "1" smd circle
			(at -0.40005 0 180)
			(size 0 0)
			(layers "F.Cu" "F.Mask" "F.Paste")
			(net "SW_PVCCINFAON_CPU0_BOOT2_R")
		)
		(pad "2" smd circle
			(at 0.40005 0 180)
			(size 0 0)
			(layers "F.Cu" "F.Mask" "F.Paste")
			(net "SW_PVCCINFAON_CPU0_BOOTR2")
		)
	)
	(footprint ""
		(layer "F.Cu")
		(at 224.074482 -57.412382 90)
		(property "Reference" "R3767"
			(at 0 0 90)
			(layer "F.SilkS")
			(hide yes)
			(effects
				(font
					(size 1.27 1.27)
				)
			)
		)
		(property "Value" ""
			(at 0 0 90)
			(layer "F.Fab")
			(effects
				(font
					(size 1.27 1.27)
				)
			)
		)
		(duplicate_pad_numbers_are_jumpers no)
		(fp_line
			(start 4.0386 -1.7526)
			(end 4.0386 1.7526)
			(stroke
				(width 0.1524)
				(type default)
			)
			(layer "F.SilkS")
		)
		(fp_line
			(start -4.0386 -1.7526)
			(end 4.0386 -1.7526)
			(stroke
				(width 0.1524)
				(type default)
			)
			(layer "F.SilkS")
		)
		(fp_line
			(start 4.0386 1.7526)
			(end -4.0386 1.7526)
			(stroke
				(width 0.1524)
				(type default)
			)
			(layer "F.SilkS")
		)
		(fp_line
			(start -4.0386 1.7526)
			(end -4.0386 -1.7526)
			(stroke
				(width 0.1524)
				(type default)
			)
			(layer "F.SilkS")
		)
		(fp_line
			(start 4.0386 -1.7526)
			(end 4.0386 1.7526)
			(stroke
				(width 0.1)
				(type default)
			)
			(layer "F.Fab")
		)
		(fp_line
			(start -4.0386 -1.7526)
			(end 4.0386 -1.7526)
			(stroke
				(width 0.1)
				(type default)
			)
			(layer "F.Fab")
		)
		(fp_line
			(start 4.0386 1.7526)
			(end -4.0386 1.7526)
			(stroke
				(width 0.1)
				(type default)
			)
			(layer "F.Fab")
		)
		(fp_line
			(start -4.0386 1.7526)
			(end -4.0386 -1.7526)
			(stroke
				(width 0.1)
				(type default)
			)
			(layer "F.Fab")
		)
		(pad "1" smd rect
			(at -3.1115 0 90)
			(size 1.524 3.2004)
			(layers "F.Cu" "F.Mask" "F.Paste")
			(net "P3V3_E1S_0")
		)
		(pad "2" smd rect
			(at 3.1115 0 90)
			(size 1.524 3.2004)
			(layers "F.Cu" "F.Mask" "F.Paste")
			(net "P3V3_E1S_0_R")
		)
	)
	(footprint ""
		(layer "F.Cu")
		(at 111.332772 -129.472182)
		(property "Reference" "R1089"
			(at 0 0 0)
			(layer "F.SilkS")
			(hide yes)
			(effects
				(font
					(size 1.27 1.27)
				)
			)
		)
		(property "Value" ""
			(at 0 0 0)
			(layer "F.Fab")
			(effects
				(font
					(size 1.27 1.27)
				)
			)
		)
		(duplicate_pad_numbers_are_jumpers no)
		(fp_line
			(start -0.7874 -0.4064)
			(end 0.7874 -0.4064)
			(stroke
				(width 0.1524)
				(type default)
			)
			(layer "F.SilkS")
		)
		(fp_line
			(start -0.7874 0.4064)
			(end -0.7874 -0.4064)
			(stroke
				(width 0.1524)
				(type default)
			)
			(layer "F.SilkS")
		)
		(fp_line
			(start 0.7874 -0.4064)
			(end 0.7874 0.4064)
			(stroke
				(width 0.1524)
				(type default)
			)
			(layer "F.SilkS")
		)
		(fp_line
			(start 0.7874 0.4064)
			(end -0.7874 0.4064)
			(stroke
				(width 0.1524)
				(type default)
			)
			(layer "F.SilkS")
		)
		(fp_line
			(start -0.67945 -0.305054)
			(end -0.12065 -0.305054)
			(stroke
				(width 0.1)
				(type default)
			)
			(layer "F.Fab")
		)
		(fp_line
			(start -0.67945 0.3048)
			(end -0.67945 -0.305054)
			(stroke
				(width 0.1)
				(type default)
			)
			(layer "F.Fab")
		)
		(fp_line
			(start -0.12065 -0.305054)
			(end -0.12065 -0.2794)
			(stroke
				(width 0.1)
				(type default)
			)
			(layer "F.Fab")
		)
		(fp_line
			(start -0.12065 -0.2794)
			(end 0.12065 -0.2794)
			(stroke
				(width 0.1)
				(type default)
			)
			(layer "F.Fab")
		)
		(fp_line
			(start -0.12065 0.2794)
			(end -0.12065 0.3048)
			(stroke
				(width 0.1)
				(type default)
			)
			(layer "F.Fab")
		)
		(fp_line
			(start -0.12065 0.3048)
			(end -0.67945 0.3048)
			(stroke
				(width 0.1)
				(type default)
			)
			(layer "F.Fab")
		)
		(fp_line
			(start 0.120396 0.2794)
			(end -0.12065 0.2794)
			(stroke
				(width 0.1)
				(type default)
			)
			(layer "F.Fab")
		)
		(fp_line
			(start 0.120396 0.3048)
			(end 0.120396 0.2794)
			(stroke
				(width 0.1)
				(type default)
			)
			(layer "F.Fab")
		)
		(fp_line
			(start 0.12065 -0.3048)
			(end 0.67945 -0.3048)
			(stroke
				(width 0.1)
				(type default)
			)
			(layer "F.Fab")
		)
		(fp_line
			(start 0.12065 -0.2794)
			(end 0.12065 -0.3048)
			(stroke
				(width 0.1)
				(type default)
			)
			(layer "F.Fab")
		)
		(fp_line
			(start 0.67945 -0.3048)
			(end 0.67945 0.3048)
			(stroke
				(width 0.1)
				(type default)
			)
			(layer "F.Fab")
		)
		(fp_line
			(start 0.67945 0.3048)
			(end 0.120396 0.3048)
			(stroke
				(width 0.1)
				(type default)
			)
			(layer "F.Fab")
		)
		(pad "1" smd circle
			(at -0.40005 0)
			(size 0 0)
			(layers "F.Cu" "F.Mask" "F.Paste")
			(net "P3V3_AUX")
		)
		(pad "2" smd circle
			(at 0.40005 0)
			(size 0 0)
			(layers "F.Cu" "F.Mask" "F.Paste")
			(net "SMB_SENSOR_M2_P0_3V3AUX_SCL")
		)
	)
)
